FILE_TYPE = CONNECTIVITY;
{Allegro Design Entry HDL 16.6-p007 (v16-6-112F) 10/10/2012}
"PAGE_NUMBER" = 20;
0"NC";
END.
